# Stackup_F0T_PDB_GPU_10L_2p36mm_IT-170GT_RTF_Rev0p2_20211201.xls — Special processing (pcb-stackup)
| Special processing : |  |
| Golden Finger(金手指) | No |
| VIPPO(Via in Pad樹脂填孔) | No |
| Back Drill(背鑽) with epoxy plug/fill | No |
| Back Drill(背鑽) without epoxy plug/fill | No |
| Laser Drill(HDI雷射鑽孔) | No |
| Low profile oxide(低棕化) | No |
